(kicad_pcb
	(version 20260206)
	(generator "pcbnew")
	(generator_version "10.0")
	(general
		(thickness 1.6)
		(legacy_teardrops no)
	)
	(paper "A4")
	(title_block
		(title "04192023_DAF0TMB3IC0_F0TG_MB_C_brd_V02_OCP.brd")
		(comment 1 "Grand Teton / footprints 236-239 of 8354")
	)
	(layers
		(0 "F.Cu" signal "TOP")
		(4 "In1.Cu" signal "GND")
		(6 "In2.Cu" signal "IN1")
		(8 "In3.Cu" signal "GND1")
		(10 "In4.Cu" signal "IN2")
		(12 "In5.Cu" signal "GND2")
		(14 "In6.Cu" signal "IN3")
		(16 "In7.Cu" signal "GND3")
		(18 "In8.Cu" signal "VCC")
		(20 "In9.Cu" signal "VCC1")
		(22 "In10.Cu" signal "GND4")
		(24 "In11.Cu" signal "IN4")
		(26 "In12.Cu" signal "GND5")
		(28 "In13.Cu" signal "IN5")
		(30 "In14.Cu" signal "GND6")
		(32 "In15.Cu" signal "IN6")
		(34 "In16.Cu" signal "GND7")
		(2 "B.Cu" signal "BOTTOM")
		(9 "F.Adhes" user "F.Adhesive")
		(11 "B.Adhes" user "B.Adhesive")
		(13 "F.Paste" user "Package Geometry/Pastemask Top")
		(15 "B.Paste" user "Package Geometry/Pastemask Bottom")
		(5 "F.SilkS" user "Ref Des/Silkscreen Top")
		(7 "B.SilkS" user "Ref Des/Silkscreen Bottom")
		(1 "F.Mask" user "Board Geometry/Soldermask Top")
		(3 "B.Mask" user "Board Geometry/Soldermask Bottom")
		(17 "Dwgs.User" user "User.Drawings")
		(19 "Cmts.User" user "User.Comments")
		(21 "Eco1.User" user "User.Eco1")
		(23 "Eco2.User" user "User.Eco2")
		(25 "Edge.Cuts" user "Board Geometry/Outline")
		(27 "Margin" user)
		(31 "F.CrtYd" user "Package Geometry/Place Bound Top")
		(29 "B.CrtYd" user "Package Geometry/Place Bound Bottom")
		(35 "F.Fab" user "Ref Des/Assembly Top")
		(33 "B.Fab" user "Ref Des/Assembly Bottom")
	)
	(footprint ""
		(layer "F.Cu")
		(at 253.10084 -92.719144 -90)
		(property "Reference" "R1639"
			(at 0 0 270)
			(layer "F.SilkS")
			(hide yes)
			(effects
				(font
					(size 1.27 1.27)
				)
			)
		)
		(property "Value" ""
			(at 0 0 270)
			(layer "F.Fab")
			(effects
				(font
					(size 1.27 1.27)
				)
			)
		)
		(duplicate_pad_numbers_are_jumpers no)
		(fp_line
			(start -0.7874 0.4064)
			(end -0.7874 -0.4064)
			(stroke
				(width 0.1524)
				(type default)
			)
			(layer "F.SilkS")
		)
		(fp_line
			(start 0.7874 0.4064)
			(end -0.7874 0.4064)
			(stroke
				(width 0.1524)
				(type default)
			)
			(layer "F.SilkS")
		)
		(fp_line
			(start -0.7874 -0.4064)
			(end 0.7874 -0.4064)
			(stroke
				(width 0.1524)
				(type default)
			)
			(layer "F.SilkS")
		)
		(fp_line
			(start 0.7874 -0.4064)
			(end 0.7874 0.4064)
			(stroke
				(width 0.1524)
				(type default)
			)
			(layer "F.SilkS")
		)
		(fp_line
			(start -0.67945 0.3048)
			(end -0.67945 -0.305054)
			(stroke
				(width 0.1)
				(type default)
			)
			(layer "F.Fab")
		)
		(fp_line
			(start -0.12065 0.3048)
			(end -0.67945 0.3048)
			(stroke
				(width 0.1)
				(type default)
			)
			(layer "F.Fab")
		)
		(fp_line
			(start 0.120396 0.3048)
			(end 0.120396 0.2794)
			(stroke
				(width 0.1)
				(type default)
			)
			(layer "F.Fab")
		)
		(fp_line
			(start 0.67945 0.3048)
			(end 0.120396 0.3048)
			(stroke
				(width 0.1)
				(type default)
			)
			(layer "F.Fab")
		)
		(fp_line
			(start -0.12065 0.2794)
			(end -0.12065 0.3048)
			(stroke
				(width 0.1)
				(type default)
			)
			(layer "F.Fab")
		)
		(fp_line
			(start 0.120396 0.2794)
			(end -0.12065 0.2794)
			(stroke
				(width 0.1)
				(type default)
			)
			(layer "F.Fab")
		)
		(fp_line
			(start -0.12065 -0.2794)
			(end 0.12065 -0.2794)
			(stroke
				(width 0.1)
				(type default)
			)
			(layer "F.Fab")
		)
		(fp_line
			(start 0.12065 -0.2794)
			(end 0.12065 -0.3048)
			(stroke
				(width 0.1)
				(type default)
			)
			(layer "F.Fab")
		)
		(fp_line
			(start 0.12065 -0.3048)
			(end 0.67945 -0.3048)
			(stroke
				(width 0.1)
				(type default)
			)
			(layer "F.Fab")
		)
		(fp_line
			(start 0.67945 -0.3048)
			(end 0.67945 0.3048)
			(stroke
				(width 0.1)
				(type default)
			)
			(layer "F.Fab")
		)
		(fp_line
			(start -0.67945 -0.305054)
			(end -0.12065 -0.305054)
			(stroke
				(width 0.1)
				(type default)
			)
			(layer "F.Fab")
		)
		(fp_line
			(start -0.12065 -0.305054)
			(end -0.12065 -0.2794)
			(stroke
				(width 0.1)
				(type default)
			)
			(layer "F.Fab")
		)
		(pad "1" smd circle
			(at -0.40005 0 270)
			(size 0 0)
			(layers "F.Cu" "F.Mask" "F.Paste")
			(net "JTAG_P0_R_TMS")
		)
		(pad "2" smd circle
			(at 0.40005 0 270)
			(size 0 0)
			(layers "F.Cu" "F.Mask" "F.Paste")
			(net "JTAG_CPU0_TMS")
		)
	)
	(footprint ""
		(layer "F.Cu")
		(at 438.107836 -166.684452 180)
		(property "Reference" "C1337"
			(at 0 0 180)
			(layer "F.SilkS")
			(hide yes)
			(effects
				(font
					(size 1.27 1.27)
				)
			)
		)
		(property "Value" ""
			(at 0 0 180)
			(layer "F.Fab")
			(effects
				(font
					(size 1.27 1.27)
				)
			)
		)
		(duplicate_pad_numbers_are_jumpers no)
		(fp_line
			(start 0.7874 0.4064)
			(end -0.7874 0.4064)
			(stroke
				(width 0.1524)
				(type default)
			)
			(layer "F.SilkS")
		)
		(fp_line
			(start 0.7874 -0.4064)
			(end 0.7874 0.4064)
			(stroke
				(width 0.1524)
				(type default)
			)
			(layer "F.SilkS")
		)
		(fp_line
			(start -0.7874 0.4064)
			(end -0.7874 -0.4064)
			(stroke
				(width 0.1524)
				(type default)
			)
			(layer "F.SilkS")
		)
		(fp_line
			(start -0.7874 -0.4064)
			(end 0.7874 -0.4064)
			(stroke
				(width 0.1524)
				(type default)
			)
			(layer "F.SilkS")
		)
		(fp_line
			(start 0.67945 0.3048)
			(end 0.120396 0.3048)
			(stroke
				(width 0.1)
				(type default)
			)
			(layer "F.Fab")
		)
		(fp_line
			(start 0.67945 -0.3048)
			(end 0.67945 0.3048)
			(stroke
				(width 0.1)
				(type default)
			)
			(layer "F.Fab")
		)
		(fp_line
			(start 0.12065 -0.2794)
			(end 0.12065 -0.3048)
			(stroke
				(width 0.1)
				(type default)
			)
			(layer "F.Fab")
		)
		(fp_line
			(start 0.12065 -0.3048)
			(end 0.67945 -0.3048)
			(stroke
				(width 0.1)
				(type default)
			)
			(layer "F.Fab")
		)
		(fp_line
			(start 0.120396 0.3048)
			(end 0.120396 0.2794)
			(stroke
				(width 0.1)
				(type default)
			)
			(layer "F.Fab")
		)
		(fp_line
			(start 0.120396 0.2794)
			(end -0.12065 0.2794)
			(stroke
				(width 0.1)
				(type default)
			)
			(layer "F.Fab")
		)
		(fp_line
			(start -0.12065 0.3048)
			(end -0.67945 0.3048)
			(stroke
				(width 0.1)
				(type default)
			)
			(layer "F.Fab")
		)
		(fp_line
			(start -0.12065 0.2794)
			(end -0.12065 0.3048)
			(stroke
				(width 0.1)
				(type default)
			)
			(layer "F.Fab")
		)
		(fp_line
			(start -0.12065 -0.2794)
			(end 0.12065 -0.2794)
			(stroke
				(width 0.1)
				(type default)
			)
			(layer "F.Fab")
		)
		(fp_line
			(start -0.12065 -0.305054)
			(end -0.12065 -0.2794)
			(stroke
				(width 0.1)
				(type default)
			)
			(layer "F.Fab")
		)
		(fp_line
			(start -0.67945 0.3048)
			(end -0.67945 -0.305054)
			(stroke
				(width 0.1)
				(type default)
			)
			(layer "F.Fab")
		)
		(fp_line
			(start -0.67945 -0.305054)
			(end -0.12065 -0.305054)
			(stroke
				(width 0.1)
				(type default)
			)
			(layer "F.Fab")
		)
		(pad "1" smd circle
			(at -0.40005 0 180)
			(size 0 0)
			(layers "F.Cu" "F.Mask" "F.Paste")
			(net "P3V3_AUX")
		)
		(pad "2" smd circle
			(at 0.40005 0 180)
			(size 0 0)
			(layers "F.Cu" "F.Mask" "F.Paste")
			(net "GND")
		)
	)
	(footprint ""
		(layer "F.Cu")
		(at 359.520236 -394.82268 90)
		(property "Reference" "C589"
			(at 0 0 90)
			(layer "F.SilkS")
			(hide yes)
			(effects
				(font
					(size 1.27 1.27)
				)
			)
		)
		(property "Value" ""
			(at 0 0 90)
			(layer "F.Fab")
			(effects
				(font
					(size 1.27 1.27)
				)
			)
		)
		(duplicate_pad_numbers_are_jumpers no)
		(fp_line
			(start 0.7874 -0.4064)
			(end 0.7874 0.4064)
			(stroke
				(width 0.1524)
				(type default)
			)
			(layer "F.SilkS")
		)
		(fp_line
			(start -0.7874 -0.4064)
			(end 0.7874 -0.4064)
			(stroke
				(width 0.1524)
				(type default)
			)
			(layer "F.SilkS")
		)
		(fp_line
			(start 0.7874 0.4064)
			(end -0.7874 0.4064)
			(stroke
				(width 0.1524)
				(type default)
			)
			(layer "F.SilkS")
		)
		(fp_line
			(start -0.7874 0.4064)
			(end -0.7874 -0.4064)
			(stroke
				(width 0.1524)
				(type default)
			)
			(layer "F.SilkS")
		)
		(fp_line
			(start -0.12065 -0.305054)
			(end -0.12065 -0.2794)
			(stroke
				(width 0.1)
				(type default)
			)
			(layer "F.Fab")
		)
		(fp_line
			(start -0.67945 -0.305054)
			(end -0.12065 -0.305054)
			(stroke
				(width 0.1)
				(type default)
			)
			(layer "F.Fab")
		)
		(fp_line
			(start 0.67945 -0.3048)
			(end 0.67945 0.3048)
			(stroke
				(width 0.1)
				(type default)
			)
			(layer "F.Fab")
		)
		(fp_line
			(start 0.12065 -0.3048)
			(end 0.67945 -0.3048)
			(stroke
				(width 0.1)
				(type default)
			)
			(layer "F.Fab")
		)
		(fp_line
			(start 0.12065 -0.2794)
			(end 0.12065 -0.3048)
			(stroke
				(width 0.1)
				(type default)
			)
			(layer "F.Fab")
		)
		(fp_line
			(start -0.12065 -0.2794)
			(end 0.12065 -0.2794)
			(stroke
				(width 0.1)
				(type default)
			)
			(layer "F.Fab")
		)
		(fp_line
			(start 0.120396 0.2794)
			(end -0.12065 0.2794)
			(stroke
				(width 0.1)
				(type default)
			)
			(layer "F.Fab")
		)
		(fp_line
			(start -0.12065 0.2794)
			(end -0.12065 0.3048)
			(stroke
				(width 0.1)
				(type default)
			)
			(layer "F.Fab")
		)
		(fp_line
			(start 0.67945 0.3048)
			(end 0.120396 0.3048)
			(stroke
				(width 0.1)
				(type default)
			)
			(layer "F.Fab")
		)
		(fp_line
			(start 0.120396 0.3048)
			(end 0.120396 0.2794)
			(stroke
				(width 0.1)
				(type default)
			)
			(layer "F.Fab")
		)
		(fp_line
			(start -0.12065 0.3048)
			(end -0.67945 0.3048)
			(stroke
				(width 0.1)
				(type default)
			)
			(layer "F.Fab")
		)
		(fp_line
			(start -0.67945 0.3048)
			(end -0.67945 -0.305054)
			(stroke
				(width 0.1)
				(type default)
			)
			(layer "F.Fab")
		)
		(pad "1" smd circle
			(at -0.40005 0 90)
			(size 0 0)
			(layers "F.Cu" "F.Mask" "F.Paste")
			(net "P1V8_CPU0_RT_1D")
		)
		(pad "2" smd circle
			(at 0.40005 0 90)
			(size 0 0)
			(layers "F.Cu" "F.Mask" "F.Paste")
			(net "GND")
		)
	)
	(footprint ""
		(layer "F.Cu")
		(at 107.45597 -178.171856 180)
		(property "Reference" "PU28"
			(at 5.34289 -4.788916 0)
			(unlocked yes)
			(layer "F.SilkS")
			(effects
				(font
					(size 0.7874 0.5842)
					(thickness 0.1524)
				)
				(justify left)
			)
		)
		(property "Value" ""
			(at 0 0 180)
			(layer "F.Fab")
			(effects
				(font
					(size 1.27 1.27)
				)
			)
		)
		(duplicate_pad_numbers_are_jumpers no)
		(fp_line
			(start 2.500122 2.999994)
			(end 2.2987 2.999994)
			(stroke
				(width 0.1524)
				(type default)
			)
			(layer "F.SilkS")
		)
		(fp_line
			(start 2.500122 2.339594)
			(end 2.500122 2.999994)
			(stroke
				(width 0.1524)
				(type default)
			)
			(layer "F.SilkS")
		)
		(fp_line
			(start 2.500122 -2.999994)
			(end 2.500122 -2.44348)
			(stroke
				(width 0.1524)
				(type default)
			)
			(layer "F.SilkS")
		)
		(fp_line
			(start 2.31394 -2.999994)
			(end 2.500122 -2.999994)
			(stroke
				(width 0.1524)
				(type default)
			)
			(layer "F.SilkS")
		)
		(fp_line
			(start -2.2987 2.999994)
			(end -2.500122 2.999994)
			(stroke
				(width 0.1524)
				(type default)
			)
			(layer "F.SilkS")
		)
		(fp_line
			(start -2.500122 2.999994)
			(end -2.500122 2.339594)
			(stroke
				(width 0.1524)
				(type default)
			)
			(layer "F.SilkS")
		)
		(fp_line
			(start -2.500122 0.6604)
			(end -2.500122 0.229108)
			(stroke
				(width 0.1524)
				(type default)
			)
			(layer "F.SilkS")
		)
		(fp_line
			(start -2.500122 -2.529078)
			(end -2.500122 -2.999994)
			(stroke
				(width 0.1524)
				(type default)
			)
			(layer "F.SilkS")
		)
		(fp_line
			(start -2.500122 -2.999994)
			(end -2.24409 -2.999994)
			(stroke
				(width 0.1524)
				(type default)
			)
			(layer "F.SilkS")
		)
		(fp_poly
			(pts
				(xy -2.819908 -2.401316) (xy -3.493262 -2.625852) (xy -3.044444 -3.074924)
			)
			(stroke
				(width 0)
				(type default)
			)
			(fill yes)
			(layer "F.SilkS")
		)
		(fp_line
			(start 2.500122 2.999994)
			(end -2.500122 2.999994)
			(stroke
				(width 0.1)
				(type default)
			)
			(layer "F.Fab")
		)
		(fp_line
			(start 2.500122 -2.999994)
			(end 2.500122 2.999994)
			(stroke
				(width 0.1)
				(type default)
			)
			(layer "F.Fab")
		)
		(fp_line
			(start -2.500122 2.999994)
			(end -2.500122 -2.999994)
			(stroke
				(width 0.1)
				(type default)
			)
			(layer "F.Fab")
		)
		(fp_line
			(start -2.500122 -2.999994)
			(end 2.500122 -2.999994)
			(stroke
				(width 0.1)
				(type default)
			)
			(layer "F.Fab")
		)
		(fp_poly
			(pts
				(xy -4.218432 -2.783078) (xy -4.218432 -1.767078) (xy -3.202432 -2.275078)
			)
			(stroke
				(width 0)
				(type default)
			)
			(fill yes)
			(layer "F.Fab")
		)
		(pad "1" smd rect
			(at -2.400046 -2.275078 270)
			(size 0.2286 0.6096)
			(layers "F.Cu" "F.Mask" "F.Paste")
			(net "PVDDCR_CPU0_P1_VOS4")
		)
		(pad "2" smd rect
			(at -2.400046 -1.82499 270)
			(size 0.2286 0.6096)
			(layers "F.Cu" "F.Mask" "F.Paste")
			(net "GND")
		)
		(pad "3" smd rect
			(at -2.400046 -1.374902 270)
			(size 0.2286 0.6096)
			(layers "F.Cu" "F.Mask" "F.Paste")
			(net "PVDDCR_CPU0_P1_VCC4")
		)
		(pad "4" smd rect
			(at -2.400046 -0.925068 270)
			(size 0.2286 0.6096)
			(layers "F.Cu" "F.Mask" "F.Paste")
			(net "PVDDCR_CPU0_P1_PVCC")
		)
		(pad "5" smd rect
			(at -2.400046 -0.47498 270)
			(size 0.2286 0.6096)
			(layers "F.Cu" "F.Mask" "F.Paste")
			(net "GND")
		)
		(pad "6" smd rect
			(at -2.400046 -0.024892 270)
			(size 0.2286 0.6096)
			(layers "F.Cu" "F.Mask" "F.Paste")
			(net "NC_PVDDCR_CPU0_P1_GL1_4")
		)
		(pad "7_9-20_24" smd circle
			(at 0 1.150112 270)
			(size 0 0)
			(layers "F.Cu" "F.Mask" "F.Paste")
			(net "GND")
		)
		(pad "10_19" smd rect
			(at 0 2.899918 270)
			(size 0.6096 4.318)
			(layers "F.Cu" "F.Mask" "F.Paste")
			(net "SW_PVDDCR_CPU0_P1_SW4")
		)
		(pad "25_29" smd rect
			(at 1.549908 -1.279906 90)
			(size 2.0574 2.3114)
			(layers "F.Cu" "F.Mask" "F.Paste")
			(net "SW_P12V_AUX_PVDDCR_CPU0_P1_FLT")
		)
		(pad "30" smd rect
			(at 2.05994 -2.899918 180)
			(size 0.2286 0.6096)
			(layers "F.Cu" "F.Mask" "F.Paste")
			(net "SW_P12V_AUX_PVDDCR_CPU0_P1_FLT")
		)
		(pad "31" smd rect
			(at 1.610106 -2.899918 180)
			(size 0.2286 0.6096)
			(layers "F.Cu" "F.Mask" "F.Paste")
			(net "NC_PVDDCR_CPU0_P1_DNC4")
		)
		(pad "32" smd rect
			(at 1.160018 -2.899918 180)
			(size 0.2286 0.6096)
			(layers "F.Cu" "F.Mask" "F.Paste")
			(net "SW_PVDDCR_CPU0_P1_PH4")
		)
		(pad "33" smd rect
			(at 0.70993 -2.899918 180)
			(size 0.2286 0.6096)
			(layers "F.Cu" "F.Mask" "F.Paste")
			(net "SW_PVDDCR_CPU0_P1_BOOT4")
		)
		(pad "34" smd rect
			(at 0.260096 -2.899918 180)
			(size 0.2286 0.6096)
			(layers "F.Cu" "F.Mask" "F.Paste")
			(net "PVDDCR_CPU0_P1_PWM4")
		)
		(pad "35" smd rect
			(at -0.189992 -2.899918 180)
			(size 0.2286 0.6096)
			(layers "F.Cu" "F.Mask" "F.Paste")
			(net "PVDDCR_CPU0_P1_VCC4")
		)
		(pad "36" smd rect
			(at -0.64008 -2.899918 180)
			(size 0.2286 0.6096)
			(layers "F.Cu" "F.Mask" "F.Paste")
			(net "PVDDCR_CPU0_P1_TEMP0")
		)
		(pad "37" smd rect
			(at -1.089914 -2.899918 180)
			(size 0.2286 0.6096)
			(layers "F.Cu" "F.Mask" "F.Paste")
			(net "PVDDCR_CPU0_P1_LSET4")
		)
		(pad "38" smd rect
			(at -1.540002 -2.899918 180)
			(size 0.2286 0.6096)
			(layers "F.Cu" "F.Mask" "F.Paste")
			(net "PVDDCR_CPU0_P1_IMON4")
		)
		(pad "39" smd rect
			(at -1.99009 -2.899918 180)
			(size 0.2286 0.6096)
			(layers "F.Cu" "F.Mask" "F.Paste")
			(net "PVDDCR_CPU0_P1_VCCS")
		)
		(pad "40" smd rect
			(at -0.87503 -1.27508 180)
			(size 1.7526 1.9558)
			(layers "F.Cu" "F.Mask" "F.Paste")
			(net "GND")
		)
		(pad "41" smd rect
			(at -1.525016 0.249936 90)
			(size 0.3048 0.4572)
			(layers "F.Cu" "F.Mask" "F.Paste")
			(net "NC_PVDDCR_CPU0_P1_GL2_4")
		)
		(zone
			(layer "F.Cu")
			(hatch none 0.5)
			(connect_pads
				(clearance 0)
			)
			(min_thickness 0.25)
			(keepout
				(tracks not_allowed)
				(vias allowed)
				(pads allowed)
				(copperpour not_allowed)
				(footprints allowed)
			)
			(placement
				(enabled no)
				(sheetname "")
			)
			(fill
				(thermal_gap 0.5)
				(thermal_bridge_width 0.5)
				(island_removal_mode 0)
			)
			(polygon
				(pts
					(xy 109.956092 -180.716174) (xy 109.956092 -180.42255) (xy 104.955848 -180.42255) (xy 104.955848 -180.716174)
					(xy 105.24617 -180.716174) (xy 109.66577 -180.716174)
				)
			)
		)
		(zone
			(layer "F.Cu")
			(hatch none 0.5)
			(connect_pads
				(clearance 0)
			)
			(min_thickness 0.25)
			(keepout
				(tracks not_allowed)
				(vias allowed)
				(pads allowed)
				(copperpour not_allowed)
				(footprints allowed)
			)
			(placement
				(enabled no)
				(sheetname "")
			)
			(fill
				(thermal_gap 0.5)
				(thermal_bridge_width 0.5)
				(island_removal_mode 0)
			)
			(polygon
				(pts
					(xy 107.4039 -177.925476) (xy 107.4039 -175.868076) (xy 109.2581 -175.868076) (xy 109.2581 -176.109122)
					(xy 109.500416 -176.109122) (xy 109.500416 -175.627538) (xy 105.57637 -175.627538) (xy 105.57637 -175.81245)
					(xy 107.112562 -175.81245) (xy 107.112562 -177.97145) (xy 104.955848 -177.97145) (xy 104.955848 -178.221132)
					(xy 107.122468 -178.221132) (xy 107.4039 -177.9397)
				)
			)
		)
	)
)
